FILE_TYPE = MACRO_DRAWING;
SET COLOR_WIRE YELLOW;
SET COLOR_PROP ORANGE;
SET COLOR_DOT WHITE;
SET COLOR_ARC YELLOW;
SET COLOR_BODY GREEN;
SET COLOR_NOTE PURPLE;
SET PROP_DISPLAY VALUE;
SET PAGE_NUMBER P247;
FORCEADD QUANTA_TITLE_BLOCK_C..1
(0 0);
FORCEPROP 1 LAST CUSTOM_TXT_CDS <NAME_2>
J 0
(-3175 50);
FORCEPROP 1 LAST CUSTOM_TXT_CDS <NAME_1>
J 0
(-3175 175);
FORCEPROP 1 LAST CUSTOM_TXT_CDS <Q_NUMBER>
J 0
(-1403 103);
DISPLAY 1.212766 (-1403 103);
FORCEPROP 1 LAST CUSTOM_TXT_CDS <Q_PROJ>
J 0
(-2382 102);
DISPLAY 1.212766 (-2382 102);
FORCEPROP 1 LAST CUSTOM_TXT_CDS <Q_REV>
J 0
(-184 103);
DISPLAY 1.212766 (-184 103);
FORCEPROP 1 LAST CUSTOM_TXT_CDS <CON_LAST_MODIFIED>
J 0
(-1885 15);
DISPLAY 0.978723 (-1885 15);
FORCEPROP 1 LAST CUSTOM_TXT_CDS <CON_PAGE_NUM> OF <CON_TOTAL_PAGES>
J 0
(-446 18);
DISPLAY 0.978723 (-446 18);
FORCEPROP 1 LAST Q_TITLE Blank
J 0
(-9366 26);
DISPLAY 2.446809 (-9366 26);
PAINT GREEN (-9366 26);
FORCEPROP 2 LAST PAGE_BORDER TRUE
J 0
(-7890 5250);
DISPLAY 0.638298 (-7890 5250);
PAINT PINK (-7890 5250);
DISPLAY INVISIBLE (-7890 5250);
FORCEPROP 1 LAST CDS_LMAN_SYM_OUTLINE -9475,6775,100,-125
J 0
(0 0);
DISPLAY 0.468085 (0 0);
PAINT GREEN (0 0);
DISPLAY INVISIBLE (0 0);
FORCEPROP 2 LAST CDS_LIB pure_quanta
J 0
(0 0);
DISPLAY INVISIBLE (0 0);
FORCEPROP 2 LAST CDS_XR_PAGE_TITLE CR-247 : @T6G_MB_LIB.T6G(SCH_1):PAGE247
J 0
(-7890 5250);
DISPLAY 0.638298 (-7890 5250);
PAINT PINK (-7890 5250);
DISPLAY INVISIBLE (-7890 5250);
FORCEPROP 2 LAST CUSTOM_TXT_CDS <XR_PAGE_TITLE>
J 0
(-7890 5250);
DISPLAY 0.638298 (-7890 5250);
PAINT PINK (-7890 5250);
DISPLAY INVISIBLE (-7890 5250);
FORCEPROP 1 LAST COMMENT_BODY TRUE
J 0
(12 -13);
DISPLAY 0.978723 (12 -13);
PAINT GREEN (12 -13);
DISPLAY INVISIBLE (12 -13);
FORCEPROP 1 LAST Q_DEPT BU9
J 1
(-3763 49);
DISPLAY 1.957447 (-3763 49);
PAINT GREEN (-3763 49);
DISPLAY INVISIBLE (-3763 49);
FORCEPROP 0 LAST CDS_CON_LAST_MODIFIED Thu Aug 24 10:15:42 2023
J 0
(-1885 15);
DISPLAY INVISIBLE (-1885 15);
QUIT
